# BASEBOARD_FAB2 (Tioga Pass) — schematic netlist excerpt (pin names and nets, part order shuffled) for the footprints in the layout excerpt that follows; sources: Cadence DE-HDL packaged netlist, KiCad conversion of Wiwynn_Tioga_Pass_MB.brd

R7D13  RES  8.2K 1% EMPTY  pkg 0402  page 125 : A = P3V3_STBY ; B = RMII_BMC_PCH_SPRNGVLLE_RXER
R8B24  RES  3.3K 5% CHIP  pkg 0402  page 138 : A = P3V3_STBY ; B = SMB_HOST_STBY_LVC3_SDA_R5
R2M1  RES  33.2 1% CHIP  pkg 0402  page 120 : A = FM_CPLD_ADR_TRIGGER_N ; B = FM_CPLD_ADR_TRIGGER_R_N

(kicad_pcb
	(version 20260206)
	(generator "pcbnew")
	(generator_version "10.0")
	(general
		(thickness 1.6)
		(legacy_teardrops no)
	)
	(paper "A4")
	(title_block
		(title "Wiwynn_Tioga_Pass_MB.brd")
		(comment 1 "Tioga Pass / footprints 1367-1369 of 4770")
	)
	(layers
		(0 "F.Cu" signal "TOP")
		(4 "In1.Cu" signal "L2GND")
		(6 "In2.Cu" signal "L3")
		(8 "In3.Cu" signal "L4GND")
		(10 "In4.Cu" signal "L5")
		(12 "In5.Cu" signal "L6GND")
		(14 "In6.Cu" signal "L7VCC")
		(16 "In7.Cu" signal "L8VCC")
		(18 "In8.Cu" signal "L9GND")
		(20 "In9.Cu" signal "L10")
		(22 "In10.Cu" signal "L11GND")
		(24 "In11.Cu" signal "L12")
		(26 "In12.Cu" signal "L13GND")
		(2 "B.Cu" signal "BOTTOM")
		(9 "F.Adhes" user "F.Adhesive")
		(11 "B.Adhes" user "B.Adhesive")
		(13 "F.Paste" user "Package Geometry/Pastemask Top")
		(15 "B.Paste" user "Package Geometry/Pastemask Bottom")
		(5 "F.SilkS" user "Ref Des/Silkscreen Top")
		(7 "B.SilkS" user "Ref Des/Silkscreen Bottom")
		(1 "F.Mask" user "Board Geometry/Soldermask Top")
		(3 "B.Mask" user "Board Geometry/Soldermask Bottom")
		(17 "Dwgs.User" user "User.Drawings")
		(19 "Cmts.User" user "User.Comments")
		(21 "Eco1.User" user "User.Eco1")
		(23 "Eco2.User" user "User.Eco2")
		(25 "Edge.Cuts" user "Board Geometry/Outline")
		(27 "Margin" user)
		(31 "F.CrtYd" user "Package Geometry/Place Bound Top")
		(29 "B.CrtYd" user "Package Geometry/Place Bound Bottom")
		(35 "F.Fab" user "Ref Des/Assembly Top")
		(33 "B.Fab" user "Ref Des/Assembly Bottom")
	)
	(footprint ""
		(layer "F.Cu")
		(at 386.0165 -85.979 90)
		(property "Reference" "R7D13"
			(at 0 0 90)
			(layer "F.SilkS")
			(hide yes)
			(effects
				(font
					(size 1.27 1.27)
				)
			)
		)
		(property "Value" ""
			(at 0 0 90)
			(layer "F.Fab")
			(effects
				(font
					(size 1.27 1.27)
				)
			)
		)
		(duplicate_pad_numbers_are_jumpers no)
		(fp_poly
			(pts
				(xy -0.2794 -0.1016) (xy 0.2794 -0.1016) (xy 0.2794 0.9906) (xy -0.2794 0.9906)
			)
			(stroke
				(width 0)
				(type default)
			)
			(fill no)
			(layer "F.CrtYd")
		)
		(fp_line
			(start 0.2794 -0.1016)
			(end -0.2794 -0.1016)
			(stroke
				(width 0.1)
				(type default)
			)
			(layer "F.Fab")
		)
		(fp_line
			(start -0.2794 -0.1016)
			(end -0.2794 0.9906)
			(stroke
				(width 0.1)
				(type default)
			)
			(layer "F.Fab")
		)
		(fp_line
			(start 0.2794 0.9906)
			(end 0.2794 -0.1016)
			(stroke
				(width 0.1)
				(type default)
			)
			(layer "F.Fab")
		)
		(fp_line
			(start -0.2794 0.9906)
			(end 0.2794 0.9906)
			(stroke
				(width 0.1)
				(type default)
			)
			(layer "F.Fab")
		)
		(pad "1" smd rect
			(at 0 0 90)
			(size 0.508 0.508)
			(layers "F.Cu" "F.Mask" "F.Paste")
			(net "P3V3_STBY")
		)
		(pad "2" smd rect
			(at 0 0.889 90)
			(size 0.508 0.508)
			(layers "F.Cu" "F.Mask" "F.Paste")
			(net "RMII_BMC_PCH_SPRNGVLLE_RXER")
		)
		(zone
			(layer "F.Cu")
			(hatch none 0.5)
			(connect_pads
				(clearance 0)
			)
			(min_thickness 0.25)
			(keepout
				(tracks allowed)
				(vias not_allowed)
				(pads allowed)
				(copperpour not_allowed)
				(footprints allowed)
			)
			(placement
				(enabled no)
				(sheetname "")
			)
			(fill
				(thermal_gap 0.5)
				(thermal_bridge_width 0.5)
				(island_removal_mode 0)
			)
			(polygon
				(pts
					(xy 386.2705 -85.725) (xy 386.2705 -86.233) (xy 386.6515 -86.233) (xy 386.6515 -85.725)
				)
			)
		)
		(zone
			(layer "F.Cu")
			(hatch none 0.5)
			(connect_pads
				(clearance 0)
			)
			(min_thickness 0.25)
			(keepout
				(tracks not_allowed)
				(vias allowed)
				(pads allowed)
				(copperpour not_allowed)
				(footprints allowed)
			)
			(placement
				(enabled no)
				(sheetname "")
			)
			(fill
				(thermal_gap 0.5)
				(thermal_bridge_width 0.5)
				(island_removal_mode 0)
			)
			(polygon
				(pts
					(xy 386.6515 -85.725) (xy 386.6515 -86.233) (xy 386.2705 -86.233) (xy 386.2705 -85.725)
				)
			)
		)
	)
	(footprint ""
		(layer "F.Cu")
		(at 415.7345 -114.935 -90)
		(property "Reference" "R2M1"
			(at 0 0 270)
			(layer "F.SilkS")
			(hide yes)
			(effects
				(font
					(size 1.27 1.27)
				)
			)
		)
		(property "Value" ""
			(at 0 0 270)
			(layer "F.Fab")
			(effects
				(font
					(size 1.27 1.27)
				)
			)
		)
		(duplicate_pad_numbers_are_jumpers no)
		(fp_poly
			(pts
				(xy -0.2794 -0.1016) (xy 0.2794 -0.1016) (xy 0.2794 0.9906) (xy -0.2794 0.9906)
			)
			(stroke
				(width 0)
				(type default)
			)
			(fill no)
			(layer "F.CrtYd")
		)
		(fp_line
			(start -0.2794 0.9906)
			(end 0.2794 0.9906)
			(stroke
				(width 0.1)
				(type default)
			)
			(layer "F.Fab")
		)
		(fp_line
			(start 0.2794 0.9906)
			(end 0.2794 -0.1016)
			(stroke
				(width 0.1)
				(type default)
			)
			(layer "F.Fab")
		)
		(fp_line
			(start -0.2794 -0.1016)
			(end -0.2794 0.9906)
			(stroke
				(width 0.1)
				(type default)
			)
			(layer "F.Fab")
		)
		(fp_line
			(start 0.2794 -0.1016)
			(end -0.2794 -0.1016)
			(stroke
				(width 0.1)
				(type default)
			)
			(layer "F.Fab")
		)
		(pad "1" smd rect
			(at 0 0 270)
			(size 0.508 0.508)
			(layers "F.Cu" "F.Mask" "F.Paste")
			(net "FM_CPLD_ADR_TRIGGER_N")
		)
		(pad "2" smd rect
			(at 0 0.889 270)
			(size 0.508 0.508)
			(layers "F.Cu" "F.Mask" "F.Paste")
			(net "FM_CPLD_ADR_TRIGGER_R_N")
		)
		(zone
			(layer "F.Cu")
			(hatch none 0.5)
			(connect_pads
				(clearance 0)
			)
			(min_thickness 0.25)
			(keepout
				(tracks not_allowed)
				(vias allowed)
				(pads allowed)
				(copperpour not_allowed)
				(footprints allowed)
			)
			(placement
				(enabled no)
				(sheetname "")
			)
			(fill
				(thermal_gap 0.5)
				(thermal_bridge_width 0.5)
				(island_removal_mode 0)
			)
			(polygon
				(pts
					(xy 415.0995 -115.189) (xy 415.0995 -114.681) (xy 415.4805 -114.681) (xy 415.4805 -115.189)
				)
			)
		)
		(zone
			(layer "F.Cu")
			(hatch none 0.5)
			(connect_pads
				(clearance 0)
			)
			(min_thickness 0.25)
			(keepout
				(tracks allowed)
				(vias not_allowed)
				(pads allowed)
				(copperpour not_allowed)
				(footprints allowed)
			)
			(placement
				(enabled no)
				(sheetname "")
			)
			(fill
				(thermal_gap 0.5)
				(thermal_bridge_width 0.5)
				(island_removal_mode 0)
			)
			(polygon
				(pts
					(xy 415.4805 -115.189) (xy 415.4805 -114.681) (xy 415.0995 -114.681) (xy 415.0995 -115.189)
				)
			)
		)
	)
	(footprint ""
		(layer "F.Cu")
		(at 461.137 -1.524 90)
		(property "Reference" "R8B24"
			(at -0.8382 -0.67818 90)
			(unlocked yes)
			(layer "F.SilkS")
			(effects
				(font
					(size 0.4064 0.254)
					(thickness 0.1524)
				)
				(justify left)
			)
		)
		(property "Value" ""
			(at 0 0 90)
			(layer "F.Fab")
			(effects
				(font
					(size 1.27 1.27)
				)
			)
		)
		(duplicate_pad_numbers_are_jumpers no)
		(fp_poly
			(pts
				(xy -0.2794 -0.1016) (xy 0.2794 -0.1016) (xy 0.2794 0.9906) (xy -0.2794 0.9906)
			)
			(stroke
				(width 0)
				(type default)
			)
			(fill no)
			(layer "F.CrtYd")
		)
		(fp_line
			(start 0.2794 -0.1016)
			(end -0.2794 -0.1016)
			(stroke
				(width 0.1)
				(type default)
			)
			(layer "F.Fab")
		)
		(fp_line
			(start -0.2794 -0.1016)
			(end -0.2794 0.9906)
			(stroke
				(width 0.1)
				(type default)
			)
			(layer "F.Fab")
		)
		(fp_line
			(start 0.2794 0.9906)
			(end 0.2794 -0.1016)
			(stroke
				(width 0.1)
				(type default)
			)
			(layer "F.Fab")
		)
		(fp_line
			(start -0.2794 0.9906)
			(end 0.2794 0.9906)
			(stroke
				(width 0.1)
				(type default)
			)
			(layer "F.Fab")
		)
		(pad "1" smd rect
			(at 0 0 90)
			(size 0.508 0.508)
			(layers "F.Cu" "F.Mask" "F.Paste")
			(net "P3V3_STBY")
		)
		(pad "2" smd rect
			(at 0 0.889 90)
			(size 0.508 0.508)
			(layers "F.Cu" "F.Mask" "F.Paste")
			(net "SMB_HOST_STBY_LVC3_SDA_R5")
		)
		(zone
			(layer "F.Cu")
			(hatch none 0.5)
			(connect_pads
				(clearance 0)
			)
			(min_thickness 0.25)
			(keepout
				(tracks allowed)
				(vias not_allowed)
				(pads allowed)
				(copperpour not_allowed)
				(footprints allowed)
			)
			(placement
				(enabled no)
				(sheetname "")
			)
			(fill
				(thermal_gap 0.5)
				(thermal_bridge_width 0.5)
				(island_removal_mode 0)
			)
			(polygon
				(pts
					(xy 461.391 -1.27) (xy 461.391 -1.778) (xy 461.772 -1.778) (xy 461.772 -1.27)
				)
			)
		)
		(zone
			(layer "F.Cu")
			(hatch none 0.5)
			(connect_pads
				(clearance 0)
			)
			(min_thickness 0.25)
			(keepout
				(tracks not_allowed)
				(vias allowed)
				(pads allowed)
				(copperpour not_allowed)
				(footprints allowed)
			)
			(placement
				(enabled no)
				(sheetname "")
			)
			(fill
				(thermal_gap 0.5)
				(thermal_bridge_width 0.5)
				(island_removal_mode 0)
			)
			(polygon
				(pts
					(xy 461.772 -1.27) (xy 461.772 -1.778) (xy 461.391 -1.778) (xy 461.391 -1.27)
				)
			)
		)
	)
)
